(kicad_pcb
	(version 20260206)
	(generator "pcbnew")
	(generator_version "10.0")
	(general
		(thickness 1.6)
		(legacy_teardrops no)
	)
	(paper "A4")
	(title_block
		(title "Bryce Canyon_IOM_M2_16342-2_OCP.brd")
		(comment 1 "Bryce Canyon / footprints 1051-1057 of 1146")
	)
	(layers
		(0 "F.Cu" signal "TOP")
		(4 "In1.Cu" signal "L2GND")
		(6 "In2.Cu" signal "L3")
		(8 "In3.Cu" signal "L4VCC")
		(10 "In4.Cu" signal "L5VCC")
		(12 "In5.Cu" signal "L6")
		(14 "In6.Cu" signal "L7GND")
		(2 "B.Cu" signal "BOTTOM")
		(9 "F.Adhes" user "F.Adhesive")
		(11 "B.Adhes" user "B.Adhesive")
		(13 "F.Paste" user "Package Geometry/Pastemask Top")
		(15 "B.Paste" user "Package Geometry/Pastemask Bottom")
		(5 "F.SilkS" user "Ref Des/Silkscreen Top")
		(7 "B.SilkS" user "Ref Des/Silkscreen Bottom")
		(1 "F.Mask" user "Board Geometry/Soldermask Top")
		(3 "B.Mask" user "Board Geometry/Soldermask Bottom")
		(17 "Dwgs.User" user "User.Drawings")
		(19 "Cmts.User" user "User.Comments")
		(21 "Eco1.User" user "User.Eco1")
		(23 "Eco2.User" user "User.Eco2")
		(25 "Edge.Cuts" user "Board Geometry/Outline")
		(27 "Margin" user)
		(31 "F.CrtYd" user "Package Geometry/Place Bound Top")
		(29 "B.CrtYd" user "Package Geometry/Place Bound Bottom")
		(35 "F.Fab" user "Ref Des/Assembly Top")
		(33 "B.Fab" user "Ref Des/Assembly Bottom")
	)
	(footprint ""
		(layer "B.Cu")
		(at 40.884856 -182.948072)
		(property "Reference" "C178"
			(at 0 0 0)
			(layer "B.SilkS")
			(hide yes)
			(effects
				(font
					(size 1.27 1.27)
				)
				(justify mirror)
			)
		)
		(property "Value" "SCD1U50V3KX-GP"
			(at 0 -2.8194 0)
			(unlocked yes)
			(layer "B.Fab")
			(hide yes)
			(effects
				(font
					(size 1.016 1.016)
					(thickness 0.1524)
				)
				(justify mirror)
			)
		)
		(property "Device Type" "C603H36"
			(at 0 -4.3434 0)
			(unlocked yes)
			(layer "B.Fab")
			(hide yes)
			(effects
				(font
					(size 1.016 1.016)
					(thickness 0.1524)
				)
				(justify mirror)
			)
		)
		(duplicate_pad_numbers_are_jumpers no)
		(fp_line
			(start -0.508 0)
			(end 0.508 0)
			(stroke
				(width 0.2032)
				(type default)
			)
			(layer "B.SilkS")
		)
		(fp_rect
			(start 0.5842 1.3335)
			(end -0.5842 -1.3335)
			(stroke
				(width 0)
				(type default)
			)
			(fill no)
			(layer "B.CrtYd")
		)
		(fp_rect
			(start 0.5842 1.3335)
			(end -0.5842 -1.3335)
			(stroke
				(width 0)
				(type default)
			)
			(fill no)
			(layer "B.Fab")
		)
		(pad "1" smd custom
			(at 0 -0.762 180)
			(size 0.2159 0.2159)
			(layers "B.Cu" "B.Mask" "B.Paste")
			(net "P3V3_VBST_RC")
			(options
				(clearance outline)
				(anchor circle)
			)
			(primitives
				(gr_poly
					(pts
						(arc
							(start -0.3302 0.4318)
							(mid -0.402042 0.402042)
							(end -0.4318 0.3302)
						)
						(arc
							(start -0.4318 -0.3302)
							(mid -0.402042 -0.402042)
							(end -0.3302 -0.4318)
						)
						(arc
							(start 0.3302 -0.4318)
							(mid 0.402042 -0.402042)
							(end 0.4318 -0.3302)
						)
						(arc
							(start 0.4318 0.3302)
							(mid 0.402042 0.402042)
							(end 0.3302 0.4318)
						)
					)
					(width 0)
					(fill yes)
				)
			)
		)
		(pad "2" smd custom
			(at 0 0.762 180)
			(size 0.2159 0.2159)
			(layers "B.Cu" "B.Mask" "B.Paste")
			(net "P3V3_STBY_LL")
			(options
				(clearance outline)
				(anchor circle)
			)
			(primitives
				(gr_poly
					(pts
						(arc
							(start -0.3302 0.4318)
							(mid -0.402042 0.402042)
							(end -0.4318 0.3302)
						)
						(arc
							(start -0.4318 -0.3302)
							(mid -0.402042 -0.402042)
							(end -0.3302 -0.4318)
						)
						(arc
							(start 0.3302 -0.4318)
							(mid 0.402042 -0.402042)
							(end 0.4318 -0.3302)
						)
						(arc
							(start 0.4318 0.3302)
							(mid 0.402042 0.402042)
							(end 0.3302 0.4318)
						)
					)
					(width 0)
					(fill yes)
				)
			)
		)
	)
	(footprint ""
		(layer "B.Cu")
		(at 47.23892 -132.09143 90)
		(property "Reference" "R183"
			(at 0 0 90)
			(layer "B.SilkS")
			(hide yes)
			(effects
				(font
					(size 1.27 1.27)
				)
				(justify mirror)
			)
		)
		(property "Value" "2K2R2F-GP"
			(at -0.064008 -3.993896 90)
			(unlocked yes)
			(layer "B.Fab")
			(hide yes)
			(effects
				(font
					(size 1.016 1.016)
					(thickness 0.1524)
				)
				(justify mirror)
			)
		)
		(property "Device Type" "R402H16"
			(at -0.064008 -5.517896 90)
			(unlocked yes)
			(layer "B.Fab")
			(hide yes)
			(effects
				(font
					(size 1.016 1.016)
					(thickness 0.1524)
				)
				(justify mirror)
			)
		)
		(duplicate_pad_numbers_are_jumpers no)
		(fp_line
			(start 0.508 -0.9398)
			(end 0.508 0.9398)
			(stroke
				(width 0.1524)
				(type default)
			)
			(layer "B.SilkS")
		)
		(fp_line
			(start -0.508 -0.9398)
			(end 0.508 -0.9398)
			(stroke
				(width 0.1524)
				(type default)
			)
			(layer "B.SilkS")
		)
		(fp_rect
			(start 0.508 0.9398)
			(end -0.508 -0.9398)
			(stroke
				(width 0)
				(type default)
			)
			(fill no)
			(layer "B.CrtYd")
		)
		(fp_rect
			(start 0.508 0.9398)
			(end -0.508 -0.9398)
			(stroke
				(width 0)
				(type default)
			)
			(fill no)
			(layer "B.Fab")
		)
		(pad "1" smd custom
			(at 0 -0.4445 270)
			(size 0.1397 0.1397)
			(layers "B.Cu" "B.Mask" "B.Paste")
			(net "I2C_IOM_SCL")
			(options
				(clearance outline)
				(anchor circle)
			)
			(primitives
				(gr_poly
					(pts
						(arc
							(start -0.1778 0.2794)
							(mid -0.249642 0.249642)
							(end -0.2794 0.1778)
						)
						(arc
							(start -0.2794 -0.1778)
							(mid -0.249642 -0.249642)
							(end -0.1778 -0.2794)
						)
						(arc
							(start 0.1778 -0.2794)
							(mid 0.249642 -0.249642)
							(end 0.2794 -0.1778)
						)
						(arc
							(start 0.2794 0.1778)
							(mid 0.249642 0.249642)
							(end 0.1778 0.2794)
						)
					)
					(width 0)
					(fill yes)
				)
			)
		)
		(pad "2" smd custom
			(at 0 0.4445 270)
			(size 0.1397 0.1397)
			(layers "B.Cu" "B.Mask" "B.Paste")
			(net "P3V3_STBY")
			(options
				(clearance outline)
				(anchor circle)
			)
			(primitives
				(gr_poly
					(pts
						(arc
							(start -0.1778 0.2794)
							(mid -0.249642 0.249642)
							(end -0.2794 0.1778)
						)
						(arc
							(start -0.2794 -0.1778)
							(mid -0.249642 -0.249642)
							(end -0.1778 -0.2794)
						)
						(arc
							(start 0.1778 -0.2794)
							(mid 0.249642 -0.249642)
							(end 0.2794 -0.1778)
						)
						(arc
							(start 0.2794 0.1778)
							(mid 0.249642 0.249642)
							(end 0.1778 0.2794)
						)
					)
					(width 0)
					(fill yes)
				)
			)
		)
	)
	(footprint ""
		(layer "B.Cu")
		(at 36.039298 -143.075914)
		(property "Reference" "C60"
			(at 0 0 0)
			(layer "B.SilkS")
			(hide yes)
			(effects
				(font
					(size 1.27 1.27)
				)
				(justify mirror)
			)
		)
		(property "Value" "SC1U16V3KX-5GP"
			(at 0 -2.8194 0)
			(unlocked yes)
			(layer "B.Fab")
			(hide yes)
			(effects
				(font
					(size 1.016 1.016)
					(thickness 0.1524)
				)
				(justify mirror)
			)
		)
		(property "Device Type" "C603H36"
			(at 0 -4.3434 0)
			(unlocked yes)
			(layer "B.Fab")
			(hide yes)
			(effects
				(font
					(size 1.016 1.016)
					(thickness 0.1524)
				)
				(justify mirror)
			)
		)
		(duplicate_pad_numbers_are_jumpers no)
		(fp_line
			(start -0.508 0)
			(end 0.508 0)
			(stroke
				(width 0.2032)
				(type default)
			)
			(layer "B.SilkS")
		)
		(fp_rect
			(start 0.5842 1.3335)
			(end -0.5842 -1.3335)
			(stroke
				(width 0)
				(type default)
			)
			(fill no)
			(layer "B.CrtYd")
		)
		(fp_rect
			(start 0.5842 1.3335)
			(end -0.5842 -1.3335)
			(stroke
				(width 0)
				(type default)
			)
			(fill no)
			(layer "B.Fab")
		)
		(pad "1" smd custom
			(at 0 -0.762 180)
			(size 0.2159 0.2159)
			(layers "B.Cu" "B.Mask" "B.Paste")
			(net "P1V2_STBY")
			(options
				(clearance outline)
				(anchor circle)
			)
			(primitives
				(gr_poly
					(pts
						(arc
							(start -0.3302 0.4318)
							(mid -0.402042 0.402042)
							(end -0.4318 0.3302)
						)
						(arc
							(start -0.4318 -0.3302)
							(mid -0.402042 -0.402042)
							(end -0.3302 -0.4318)
						)
						(arc
							(start 0.3302 -0.4318)
							(mid 0.402042 -0.402042)
							(end 0.4318 -0.3302)
						)
						(arc
							(start 0.4318 0.3302)
							(mid 0.402042 0.402042)
							(end 0.3302 0.4318)
						)
					)
					(width 0)
					(fill yes)
				)
			)
		)
		(pad "2" smd custom
			(at 0 0.762 180)
			(size 0.2159 0.2159)
			(layers "B.Cu" "B.Mask" "B.Paste")
			(net "GND")
			(options
				(clearance outline)
				(anchor circle)
			)
			(primitives
				(gr_poly
					(pts
						(arc
							(start -0.3302 0.4318)
							(mid -0.402042 0.402042)
							(end -0.4318 0.3302)
						)
						(arc
							(start -0.4318 -0.3302)
							(mid -0.402042 -0.402042)
							(end -0.3302 -0.4318)
						)
						(arc
							(start 0.3302 -0.4318)
							(mid 0.402042 -0.402042)
							(end 0.4318 -0.3302)
						)
						(arc
							(start 0.4318 0.3302)
							(mid 0.402042 0.402042)
							(end 0.3302 0.4318)
						)
					)
					(width 0)
					(fill yes)
				)
			)
		)
	)
	(footprint ""
		(layer "B.Cu")
		(at 132.6261 -17.30756)
		(property "Reference" "Q24"
			(at 0 0 0)
			(layer "B.SilkS")
			(hide yes)
			(effects
				(font
					(size 1.27 1.27)
				)
				(justify mirror)
			)
		)
		(property "Value" "2N7002K-1-GP"
			(at -0.127 -8.9662 0)
			(unlocked yes)
			(layer "B.Fab")
			(hide yes)
			(effects
				(font
					(size 1.016 1.016)
					(thickness 0.1524)
				)
				(justify mirror)
			)
		)
		(property "Device Type" "SOT23DGS2D4H44"
			(at -0.127 -10.4902 0)
			(unlocked yes)
			(layer "B.Fab")
			(hide yes)
			(effects
				(font
					(size 1.016 1.016)
					(thickness 0.1524)
				)
				(justify mirror)
			)
		)
		(duplicate_pad_numbers_are_jumpers no)
		(fp_line
			(start -1.651 -1.778)
			(end 1.651 -1.778)
			(stroke
				(width 0.1524)
				(type default)
			)
			(layer "B.SilkS")
		)
		(fp_line
			(start -1.651 1.778)
			(end -1.651 -1.778)
			(stroke
				(width 0.1524)
				(type default)
			)
			(layer "B.SilkS")
		)
		(fp_line
			(start 1.651 -1.778)
			(end 1.651 1.778)
			(stroke
				(width 0.1524)
				(type default)
			)
			(layer "B.SilkS")
		)
		(fp_line
			(start 1.651 1.778)
			(end -1.651 1.778)
			(stroke
				(width 0.1524)
				(type default)
			)
			(layer "B.SilkS")
		)
		(fp_poly
			(pts
				(xy 1.778 1.8796) (xy 1.778 -1.8796) (xy -1.778 -1.8796) (xy -1.778 1.8796)
			)
			(stroke
				(width 0)
				(type default)
			)
			(fill no)
			(layer "B.CrtYd")
		)
		(fp_poly
			(pts
				(xy 1.778 1.8796) (xy 1.778 -1.8796) (xy -1.778 -1.8796) (xy -1.778 1.8796)
			)
			(stroke
				(width 0)
				(type default)
			)
			(fill no)
			(layer "B.Fab")
		)
		(pad "D" smd custom
			(at 0 -0.9525 180)
			(size 0.1905 0.1905)
			(layers "B.Cu" "B.Mask" "B.Paste")
			(net "IOM_ADM1278_EN")
			(options
				(clearance outline)
				(anchor circle)
			)
			(primitives
				(gr_poly
					(pts
						(arc
							(start -0.1778 -0.5715)
							(mid -0.321484 -0.511984)
							(end -0.381 -0.3683)
						)
						(arc
							(start -0.381 0.3683)
							(mid -0.321484 0.511984)
							(end -0.1778 0.5715)
						)
						(arc
							(start 0.1778 0.5715)
							(mid 0.321484 0.511984)
							(end 0.381 0.3683)
						)
						(arc
							(start 0.381 -0.3683)
							(mid 0.321484 -0.511984)
							(end 0.1778 -0.5715)
						)
					)
					(width 0)
					(fill yes)
				)
			)
		)
		(pad "G" smd custom
			(at 0.98425 0.9525 180)
			(size 0.1905 0.1905)
			(layers "B.Cu" "B.Mask" "B.Paste")
			(net "IOM_MATED_N")
			(options
				(clearance outline)
				(anchor circle)
			)
			(primitives
				(gr_poly
					(pts
						(arc
							(start -0.1778 -0.5715)
							(mid -0.321484 -0.511984)
							(end -0.381 -0.3683)
						)
						(arc
							(start -0.381 0.3683)
							(mid -0.321484 0.511984)
							(end -0.1778 0.5715)
						)
						(arc
							(start 0.1778 0.5715)
							(mid 0.321484 0.511984)
							(end 0.381 0.3683)
						)
						(arc
							(start 0.381 -0.3683)
							(mid 0.321484 -0.511984)
							(end 0.1778 -0.5715)
						)
					)
					(width 0)
					(fill yes)
				)
			)
		)
		(pad "S" smd custom
			(at -0.98425 0.9525 180)
			(size 0.1905 0.1905)
			(layers "B.Cu" "B.Mask" "B.Paste")
			(net "GND")
			(options
				(clearance outline)
				(anchor circle)
			)
			(primitives
				(gr_poly
					(pts
						(arc
							(start -0.1778 -0.5715)
							(mid -0.321484 -0.511984)
							(end -0.381 -0.3683)
						)
						(arc
							(start -0.381 0.3683)
							(mid -0.321484 0.511984)
							(end -0.1778 0.5715)
						)
						(arc
							(start 0.1778 0.5715)
							(mid 0.321484 0.511984)
							(end 0.381 0.3683)
						)
						(arc
							(start 0.381 -0.3683)
							(mid 0.321484 -0.511984)
							(end 0.1778 -0.5715)
						)
					)
					(width 0)
					(fill yes)
				)
			)
		)
	)
	(footprint ""
		(layer "B.Cu")
		(at 42.533316 -134.410958 180)
		(property "Reference" "R374"
			(at 0 0 0)
			(layer "B.SilkS")
			(hide yes)
			(effects
				(font
					(size 1.27 1.27)
				)
				(justify mirror)
			)
		)
		(property "Value" "4K7R2F-GP"
			(at -0.064008 -3.993896 180)
			(unlocked yes)
			(layer "B.Fab")
			(hide yes)
			(effects
				(font
					(size 1.016 1.016)
					(thickness 0.1524)
				)
				(justify mirror)
			)
		)
		(property "Device Type" "R402H16"
			(at -0.064008 -5.517896 180)
			(unlocked yes)
			(layer "B.Fab")
			(hide yes)
			(effects
				(font
					(size 1.016 1.016)
					(thickness 0.1524)
				)
				(justify mirror)
			)
		)
		(duplicate_pad_numbers_are_jumpers no)
		(fp_line
			(start 0.508 -0.9398)
			(end 0.508 0.9398)
			(stroke
				(width 0.1524)
				(type default)
			)
			(layer "B.SilkS")
		)
		(fp_line
			(start -0.508 -0.9398)
			(end 0.508 -0.9398)
			(stroke
				(width 0.1524)
				(type default)
			)
			(layer "B.SilkS")
		)
		(fp_rect
			(start 0.508 0.9398)
			(end -0.508 -0.9398)
			(stroke
				(width 0)
				(type default)
			)
			(fill no)
			(layer "B.CrtYd")
		)
		(fp_rect
			(start 0.508 0.9398)
			(end -0.508 -0.9398)
			(stroke
				(width 0)
				(type default)
			)
			(fill no)
			(layer "B.Fab")
		)
		(pad "1" smd custom
			(at 0 -0.4445)
			(size 0.1397 0.1397)
			(layers "B.Cu" "B.Mask" "B.Paste")
			(net "P3V3_STBY")
			(options
				(clearance outline)
				(anchor circle)
			)
			(primitives
				(gr_poly
					(pts
						(arc
							(start -0.1778 0.2794)
							(mid -0.249642 0.249642)
							(end -0.2794 0.1778)
						)
						(arc
							(start -0.2794 -0.1778)
							(mid -0.249642 -0.249642)
							(end -0.1778 -0.2794)
						)
						(arc
							(start 0.1778 -0.2794)
							(mid 0.249642 -0.249642)
							(end 0.2794 -0.1778)
						)
						(arc
							(start 0.2794 0.1778)
							(mid 0.249642 0.249642)
							(end 0.1778 0.2794)
						)
					)
					(width 0)
					(fill yes)
				)
			)
		)
		(pad "2" smd custom
			(at 0 0.4445)
			(size 0.1397 0.1397)
			(layers "B.Cu" "B.Mask" "B.Paste")
			(net "BMC_GPIOS6")
			(options
				(clearance outline)
				(anchor circle)
			)
			(primitives
				(gr_poly
					(pts
						(arc
							(start -0.1778 0.2794)
							(mid -0.249642 0.249642)
							(end -0.2794 0.1778)
						)
						(arc
							(start -0.2794 -0.1778)
							(mid -0.249642 -0.249642)
							(end -0.1778 -0.2794)
						)
						(arc
							(start 0.1778 -0.2794)
							(mid 0.249642 -0.249642)
							(end 0.2794 -0.1778)
						)
						(arc
							(start 0.2794 0.1778)
							(mid 0.249642 0.249642)
							(end 0.1778 0.2794)
						)
					)
					(width 0)
					(fill yes)
				)
			)
		)
	)
	(footprint ""
		(layer "B.Cu")
		(at 60.2488 -150.749 -90)
		(property "Reference" "R398"
			(at 0 0 90)
			(layer "B.SilkS")
			(hide yes)
			(effects
				(font
					(size 1.27 1.27)
				)
				(justify mirror)
			)
		)
		(property "Value" "4K7R2F-GP"
			(at -0.064008 -3.993896 270)
			(unlocked yes)
			(layer "B.Fab")
			(hide yes)
			(effects
				(font
					(size 1.016 1.016)
					(thickness 0.1524)
				)
				(justify mirror)
			)
		)
		(property "Device Type" "R402H16"
			(at -0.064008 -5.517896 270)
			(unlocked yes)
			(layer "B.Fab")
			(hide yes)
			(effects
				(font
					(size 1.016 1.016)
					(thickness 0.1524)
				)
				(justify mirror)
			)
		)
		(duplicate_pad_numbers_are_jumpers no)
		(fp_line
			(start -0.508 -0.9398)
			(end 0.508 -0.9398)
			(stroke
				(width 0.1524)
				(type default)
			)
			(layer "B.SilkS")
		)
		(fp_line
			(start 0.508 -0.9398)
			(end 0.508 0.9398)
			(stroke
				(width 0.1524)
				(type default)
			)
			(layer "B.SilkS")
		)
		(fp_rect
			(start 0.508 0.9398)
			(end -0.508 -0.9398)
			(stroke
				(width 0)
				(type default)
			)
			(fill no)
			(layer "B.CrtYd")
		)
		(fp_rect
			(start 0.508 0.9398)
			(end -0.508 -0.9398)
			(stroke
				(width 0)
				(type default)
			)
			(fill no)
			(layer "B.Fab")
		)
		(pad "1" smd custom
			(at 0 -0.4445 90)
			(size 0.1397 0.1397)
			(layers "B.Cu" "B.Mask" "B.Paste")
			(net "GND")
			(options
				(clearance outline)
				(anchor circle)
			)
			(primitives
				(gr_poly
					(pts
						(arc
							(start -0.1778 0.2794)
							(mid -0.249642 0.249642)
							(end -0.2794 0.1778)
						)
						(arc
							(start -0.2794 -0.1778)
							(mid -0.249642 -0.249642)
							(end -0.1778 -0.2794)
						)
						(arc
							(start 0.1778 -0.2794)
							(mid 0.249642 -0.249642)
							(end 0.2794 -0.1778)
						)
						(arc
							(start 0.2794 0.1778)
							(mid 0.249642 0.249642)
							(end 0.1778 0.2794)
						)
					)
					(width 0)
					(fill yes)
				)
			)
		)
		(pad "2" smd custom
			(at 0 0.4445 90)
			(size 0.1397 0.1397)
			(layers "B.Cu" "B.Mask" "B.Paste")
			(net "MAC2_TXD2")
			(options
				(clearance outline)
				(anchor circle)
			)
			(primitives
				(gr_poly
					(pts
						(arc
							(start -0.1778 0.2794)
							(mid -0.249642 0.249642)
							(end -0.2794 0.1778)
						)
						(arc
							(start -0.2794 -0.1778)
							(mid -0.249642 -0.249642)
							(end -0.1778 -0.2794)
						)
						(arc
							(start 0.1778 -0.2794)
							(mid 0.249642 -0.249642)
							(end 0.2794 -0.1778)
						)
						(arc
							(start 0.2794 0.1778)
							(mid 0.249642 0.249642)
							(end 0.1778 0.2794)
						)
					)
					(width 0)
					(fill yes)
				)
			)
		)
	)
	(footprint ""
		(layer "B.Cu")
		(at 47.854616 -161.59226 90)
		(property "Reference" "R281"
			(at 0 0 90)
			(layer "B.SilkS")
			(hide yes)
			(effects
				(font
					(size 1.27 1.27)
				)
				(justify mirror)
			)
		)
		(property "Value" "0R2J-2-GP"
			(at -0.064008 -3.993896 90)
			(unlocked yes)
			(layer "B.Fab")
			(hide yes)
			(effects
				(font
					(size 1.016 1.016)
					(thickness 0.1524)
				)
				(justify mirror)
			)
		)
		(property "Device Type" "R402H16"
			(at -0.064008 -5.517896 90)
			(unlocked yes)
			(layer "B.Fab")
			(hide yes)
			(effects
				(font
					(size 1.016 1.016)
					(thickness 0.1524)
				)
				(justify mirror)
			)
		)
		(duplicate_pad_numbers_are_jumpers no)
		(fp_line
			(start 0.508 -0.9398)
			(end 0.508 0.9398)
			(stroke
				(width 0.1524)
				(type default)
			)
			(layer "B.SilkS")
		)
		(fp_line
			(start -0.508 -0.9398)
			(end 0.508 -0.9398)
			(stroke
				(width 0.1524)
				(type default)
			)
			(layer "B.SilkS")
		)
		(fp_rect
			(start 0.508 0.9398)
			(end -0.508 -0.9398)
			(stroke
				(width 0)
				(type default)
			)
			(fill no)
			(layer "B.CrtYd")
		)
		(fp_rect
			(start 0.508 0.9398)
			(end -0.508 -0.9398)
			(stroke
				(width 0)
				(type default)
			)
			(fill no)
			(layer "B.Fab")
		)
		(pad "1" smd custom
			(at 0 -0.4445 270)
			(size 0.1397 0.1397)
			(layers "B.Cu" "B.Mask" "B.Paste")
			(net "I2C_MEZZ_OOB_SDA")
			(options
				(clearance outline)
				(anchor circle)
			)
			(primitives
				(gr_poly
					(pts
						(arc
							(start -0.1778 0.2794)
							(mid -0.249642 0.249642)
							(end -0.2794 0.1778)
						)
						(arc
							(start -0.2794 -0.1778)
							(mid -0.249642 -0.249642)
							(end -0.1778 -0.2794)
						)
						(arc
							(start 0.1778 -0.2794)
							(mid 0.249642 -0.249642)
							(end 0.2794 -0.1778)
						)
						(arc
							(start 0.2794 0.1778)
							(mid 0.249642 0.249642)
							(end 0.1778 0.2794)
						)
					)
					(width 0)
					(fill yes)
				)
			)
		)
		(pad "2" smd custom
			(at 0 0.4445 270)
			(size 0.1397 0.1397)
			(layers "B.Cu" "B.Mask" "B.Paste")
			(net "BMC_SMB5_DAT")
			(options
				(clearance outline)
				(anchor circle)
			)
			(primitives
				(gr_poly
					(pts
						(arc
							(start -0.1778 0.2794)
							(mid -0.249642 0.249642)
							(end -0.2794 0.1778)
						)
						(arc
							(start -0.2794 -0.1778)
							(mid -0.249642 -0.249642)
							(end -0.1778 -0.2794)
						)
						(arc
							(start 0.1778 -0.2794)
							(mid 0.249642 -0.249642)
							(end 0.2794 -0.1778)
						)
						(arc
							(start 0.2794 0.1778)
							(mid 0.249642 0.249642)
							(end 0.1778 0.2794)
						)
					)
					(width 0)
					(fill yes)
				)
			)
		)
	)
)
